FILE_TYPE = MACRO_DRAWING;
SET COLOR_WIRE YELLOW;
SET COLOR_PROP ORANGE;
SET COLOR_DOT WHITE;
SET COLOR_ARC YELLOW;
SET COLOR_BODY GREEN;
SET COLOR_NOTE PURPLE;
SET PROP_DISPLAY VALUE;
SET PAGE_NUMBER P264;
FORCEADD UNIVERSAL_GND..1
(-3750 2150);
FORCEPROP 3 LASTPIN (-3750 2200) SIG_NAME GND\g
J 0
(-3740 2210);
DISPLAY 0.659574 (-3740 2210);
PAINT MONO (-3740 2210);
DISPLAY INVISIBLE (-3740 2210);
FORCEPROP 2 LAST CDS_LIB pure_quanta_power
J 0
(-3750 2150);
DISPLAY INVISIBLE (-3750 2150);
FORCEPROP 1 LAST HDL_POWER GND
J 1
(-3725 2075);
DISPLAY 0.872340 (-3725 2075);
PAINT GREEN (-3725 2075);
DISPLAY INVISIBLE (-3725 2075);
FORCEPROP 1 LAST PATH I16
J 0
(-3675 2150);
DISPLAY 0.872340 (-3675 2150);
PAINT AQUA (-3675 2150);
DISPLAY INVISIBLE (-3675 2150);
FORCEADD Q_RES..1
(-3575 2025);
FORCEPROP 1 LAST LOCATION R1363
J 0
(-3475 2025);
DISPLAY 0.489362 (-3475 2025);
PAINT SKYBLUE (-3475 2025);
FORCEPROP 0 LAST $SEC 1
J 0
(-3475 2075);
DISPLAY 0.680851 (-3475 2075);
PAINT MONO (-3475 2075);
DISPLAY INVISIBLE (-3475 2075);
FORCEPROP 0 LAST CDS_SEC 1
J 0
(-3475 2075);
DISPLAY 0.680851 (-3475 2075);
DISPLAY INVISIBLE (-3475 2075);
FORCEPROP 1 LASTPIN (-3675 2025) $PN 1
J 0
(-3663 2037);
DISPLAY 0.489362 (-3663 2037);
PAINT MONO (-3663 2037);
FORCEPROP 1 LASTPIN (-3475 2025) $PN 2
J 0
(-3513 2037);
DISPLAY 0.489362 (-3513 2037);
PAINT MONO (-3513 2037);
FORCEPROP 1 LAST VALUE 33
J 2
(-3700 2025);
DISPLAY 0.489362 (-3700 2025);
PAINT SKYBLUE (-3700 2025);
FORCEPROP 1 LAST PACK_TYPE 0402LF
J 2
(-3400 1950);
DISPLAY 0.489362 (-3400 1950);
PAINT SKYBLUE (-3400 1950);
DISPLAY INVISIBLE (-3400 1950);
FORCEPROP 1 LAST TOLERANCE 5%
J 0
(-3700 2000);
DISPLAY 0.489362 (-3700 2000);
PAINT SKYBLUE (-3700 2000);
DISPLAY INVISIBLE (-3700 2000);
FORCEPROP 1 LAST MATERIAL CHIP
J 2
(-3400 2000);
DISPLAY 0.489362 (-3400 2000);
PAINT SKYBLUE (-3400 2000);
DISPLAY INVISIBLE (-3400 2000);
FORCEPROP 1 LAST WATTAGE 1/16W
J 2
(-3650 1950);
DISPLAY 0.489362 (-3650 1950);
PAINT SKYBLUE (-3650 1950);
DISPLAY INVISIBLE (-3650 1950);
FORCEPROP 2 LAST BOM_COST MEM
J 2
(-3550 2175);
DISPLAY 0.744681 (-3550 2175);
PAINT WHITE (-3550 2175);
DISPLAY INVISIBLE (-3550 2175);
FORCEPROP 2 LAST CDS_LIB pure_quanta
J 0
(-3575 2025);
DISPLAY INVISIBLE (-3575 2025);
FORCEPROP 1 LAST PATH I17
J 0
(-3625 2175);
DISPLAY 0.978723 (-3625 2175);
PAINT WHITE (-3625 2175);
DISPLAY INVISIBLE (-3625 2175);
FORCEPROP 1 LAST PART_NUMBER CS03302JB10
J 2
(-3475 2075);
DISPLAY 0.489362 (-3475 2075);
PAINT SKYBLUE (-3475 2075);
DISPLAY INVISIBLE (-3475 2075);
FORCEADD OFFPAGE..2
(-2850 2025);
FORCEPROP 2 LAST $XR0 81 
J 0
(-2661 2025);
DISPLAY 0.638298 (-2661 2025);
PAINT MONO (-2661 2025);
FORCEPROP 2 LAST CDS_LIB standard
J 0
(-2850 2025);
DISPLAY INVISIBLE (-2850 2025);
FORCEPROP 1 LAST OFFPAGE TRUE
J 0
(-2525 1900);
DISPLAY 0.872340 (-2525 1900);
PAINT GREEN (-2525 1900);
DISPLAY INVISIBLE (-2525 1900);
FORCEPROP 1 LAST COMMENT_BODY TRUE
J 0
(-2895 1930);
DISPLAY 0.872340 (-2895 1930);
PAINT GREEN (-2895 1930);
DISPLAY INVISIBLE (-2895 1930);
FORCEPROP 2 LAST PATH I18
J 0
(-2650 2075);
DISPLAY 0.680851 (-2650 2075);
DISPLAY INVISIBLE (-2650 2075);
FORCEADD OFFPAGE..1
(-6375 2075);
FORCEPROP 2 LAST $XR0 260 
J 0
(-6627 2075);
DISPLAY 0.638298 (-6627 2075);
PAINT MONO (-6627 2075);
FORCEPROP 2 LAST CDS_LIB standard
J 0
(-6375 2075);
DISPLAY INVISIBLE (-6375 2075);
FORCEPROP 1 LAST OFFPAGE TRUE
J 0
(-6050 1950);
DISPLAY 0.872340 (-6050 1950);
PAINT GREEN (-6050 1950);
DISPLAY INVISIBLE (-6050 1950);
FORCEPROP 1 LAST COMMENT_BODY TRUE
J 0
(-6250 1975);
DISPLAY 0.872340 (-6250 1975);
PAINT GREEN (-6250 1975);
DISPLAY INVISIBLE (-6250 1975);
FORCEPROP 2 LAST PATH I2
J 0
(-6625 2125);
DISPLAY 0.680851 (-6625 2125);
DISPLAY INVISIBLE (-6625 2125);
FORCEADD UNIVERSAL_GND..1
(-6175 3725);
FORCEPROP 3 LASTPIN (-6175 3775) SIG_NAME GND\g
J 0
(-6165 3785);
DISPLAY 0.659574 (-6165 3785);
PAINT MONO (-6165 3785);
DISPLAY INVISIBLE (-6165 3785);
FORCEPROP 2 LAST CDS_LIB pure_quanta_power
J 0
(-6175 3725);
DISPLAY INVISIBLE (-6175 3725);
FORCEPROP 2 LAST BOM_COST VR_SYSTEM
J 0
(-6500 3800);
DISPLAY 0.617021 (-6500 3800);
PAINT PURPLE (-6500 3800);
DISPLAY INVISIBLE (-6500 3800);
FORCEPROP 1 LAST HDL_POWER GND
J 1
(-6150 3650);
DISPLAY 0.872340 (-6150 3650);
PAINT GREEN (-6150 3650);
DISPLAY INVISIBLE (-6150 3650);
FORCEPROP 1 LAST PATH I23
J 0
(-6100 3725);
DISPLAY 0.872340 (-6100 3725);
PAINT AQUA (-6100 3725);
DISPLAY INVISIBLE (-6100 3725);
FORCEADD Q_RES..2
(-6175 3925);
FORCEPROP 1 LAST LOCATION R1441
J 0
(-6130 4050);
DISPLAY 0.489362 (-6130 4050);
PAINT SKYBLUE (-6130 4050);
FORCEPROP 0 LAST $SEC 1
J 0
(-6125 4100);
DISPLAY 0.680851 (-6125 4100);
PAINT MONO (-6125 4100);
DISPLAY INVISIBLE (-6125 4100);
FORCEPROP 0 LAST CDS_SEC 1
J 0
(-6125 4100);
DISPLAY 0.680851 (-6125 4100);
DISPLAY INVISIBLE (-6125 4100);
FORCEPROP 1 LASTPIN (-6175 4025) $PN 1
J 0
(-6170 3987);
DISPLAY 0.489362 (-6170 3987);
PAINT MONO (-6170 3987);
FORCEPROP 1 LASTPIN (-6175 3825) $PN 2
J 0
(-6170 3835);
DISPLAY 0.489362 (-6170 3835);
PAINT MONO (-6170 3835);
FORCEPROP 1 LAST VALUE 16.9K
J 0
(-6130 4000);
DISPLAY 0.489362 (-6130 4000);
PAINT SKYBLUE (-6130 4000);
FORCEPROP 1 LAST WATTAGE 1/16W
J 0
(-6135 3900);
DISPLAY 0.489362 (-6135 3900);
PAINT SKYBLUE (-6135 3900);
FORCEPROP 1 LAST MATERIAL CHIP
J 0
(-6135 3850);
DISPLAY 0.489362 (-6135 3850);
PAINT SKYBLUE (-6135 3850);
FORCEPROP 1 LAST PACK_TYPE 0402LF
J 0
(-6135 3750);
DISPLAY 0.489362 (-6135 3750);
PAINT SKYBLUE (-6135 3750);
FORCEPROP 1 LAST TOLERANCE 1%
J 0
(-6130 3950);
DISPLAY 0.489362 (-6130 3950);
PAINT SKYBLUE (-6130 3950);
FORCEPROP 2 LAST BOM_COST VR_SYSTEM
J 0
(-6125 4100);
DISPLAY 0.680851 (-6125 4100);
DISPLAY INVISIBLE (-6125 4100);
FORCEPROP 2 LAST CDS_LIB pure_quanta
J 0
(-6175 3925);
DISPLAY INVISIBLE (-6175 3925);
FORCEPROP 1 LAST PATH I24
J 0
(-6125 4100);
DISPLAY 0.978723 (-6125 4100);
PAINT WHITE (-6125 4100);
DISPLAY INVISIBLE (-6125 4100);
FORCEPROP 1 LAST PART_NUMBER CS31692FB03
J 0
(-6135 3800);
DISPLAY 0.489362 (-6135 3800);
PAINT SKYBLUE (-6135 3800);
DISPLAY INVISIBLE (-6135 3800);
FORCEADD Q_RES..2
(-6175 4425);
FORCEPROP 1 LAST LOCATION R1440
J 0
(-6130 4550);
DISPLAY 0.489362 (-6130 4550);
PAINT SKYBLUE (-6130 4550);
FORCEPROP 0 LAST $SEC 1
J 0
(-6125 4600);
DISPLAY 0.680851 (-6125 4600);
PAINT MONO (-6125 4600);
DISPLAY INVISIBLE (-6125 4600);
FORCEPROP 0 LAST CDS_SEC 1
J 0
(-6125 4600);
DISPLAY 0.680851 (-6125 4600);
DISPLAY INVISIBLE (-6125 4600);
FORCEPROP 1 LASTPIN (-6175 4525) $PN 1
J 0
(-6170 4487);
DISPLAY 0.489362 (-6170 4487);
PAINT MONO (-6170 4487);
FORCEPROP 1 LASTPIN (-6175 4325) $PN 2
J 0
(-6170 4335);
DISPLAY 0.489362 (-6170 4335);
PAINT MONO (-6170 4335);
FORCEPROP 1 LAST PACK_TYPE 0402LF
J 0
(-6135 4250);
DISPLAY 0.489362 (-6135 4250);
PAINT SKYBLUE (-6135 4250);
FORCEPROP 1 LAST VALUE 100K
J 0
(-6130 4500);
DISPLAY 0.489362 (-6130 4500);
PAINT SKYBLUE (-6130 4500);
FORCEPROP 1 LAST MATERIAL CHIP
J 0
(-6135 4350);
DISPLAY 0.489362 (-6135 4350);
PAINT SKYBLUE (-6135 4350);
FORCEPROP 1 LAST WATTAGE 1/16W
J 0
(-6135 4400);
DISPLAY 0.489362 (-6135 4400);
PAINT SKYBLUE (-6135 4400);
FORCEPROP 1 LAST TOLERANCE 1%
J 0
(-6130 4450);
DISPLAY 0.489362 (-6130 4450);
PAINT SKYBLUE (-6130 4450);
FORCEPROP 2 LAST CDS_LIB pure_quanta
J 0
(-6175 4425);
DISPLAY INVISIBLE (-6175 4425);
FORCEPROP 2 LAST BOM_COST VR_SYSTEM
J 0
(-6125 4600);
DISPLAY 0.680851 (-6125 4600);
DISPLAY INVISIBLE (-6125 4600);
FORCEPROP 1 LAST PATH I25
J 0
(-6125 4600);
DISPLAY 0.978723 (-6125 4600);
PAINT WHITE (-6125 4600);
DISPLAY INVISIBLE (-6125 4600);
FORCEPROP 1 LAST PART_NUMBER CS41002FB09
J 0
(-6135 4300);
DISPLAY 0.489362 (-6135 4300);
PAINT SKYBLUE (-6135 4300);
DISPLAY INVISIBLE (-6135 4300);
FORCEADD Q_RES..2
(-5425 4700);
FORCEPROP 1 LAST LOCATION R1449
J 0
(-5380 4825);
DISPLAY 0.489362 (-5380 4825);
PAINT SKYBLUE (-5380 4825);
FORCEPROP 0 LAST $SEC 1
J 0
(-5375 4875);
DISPLAY 0.680851 (-5375 4875);
PAINT MONO (-5375 4875);
DISPLAY INVISIBLE (-5375 4875);
FORCEPROP 0 LAST CDS_SEC 1
J 0
(-5375 4875);
DISPLAY 0.680851 (-5375 4875);
DISPLAY INVISIBLE (-5375 4875);
FORCEPROP 1 LASTPIN (-5425 4800) $PN 1
J 0
(-5420 4762);
DISPLAY 0.489362 (-5420 4762);
PAINT MONO (-5420 4762);
FORCEPROP 1 LASTPIN (-5425 4600) $PN 2
J 0
(-5420 4610);
DISPLAY 0.489362 (-5420 4610);
PAINT MONO (-5420 4610);
FORCEPROP 1 LAST VALUE 10K
J 0
(-5380 4775);
DISPLAY 0.489362 (-5380 4775);
PAINT SKYBLUE (-5380 4775);
FORCEPROP 1 LAST PACK_TYPE 0402LF
J 0
(-5385 4525);
DISPLAY 0.489362 (-5385 4525);
PAINT SKYBLUE (-5385 4525);
FORCEPROP 1 LAST TOLERANCE 5%
J 0
(-5380 4725);
DISPLAY 0.489362 (-5380 4725);
PAINT SKYBLUE (-5380 4725);
FORCEPROP 1 LAST WATTAGE 1/16W
J 0
(-5385 4675);
DISPLAY 0.489362 (-5385 4675);
PAINT SKYBLUE (-5385 4675);
FORCEPROP 1 LAST MATERIAL CHIP
J 0
(-5385 4625);
DISPLAY 0.489362 (-5385 4625);
PAINT SKYBLUE (-5385 4625);
FORCEPROP 2 LAST BOM_COST VR_SYSTEM
J 0
(-5375 4875);
DISPLAY 0.680851 (-5375 4875);
DISPLAY INVISIBLE (-5375 4875);
FORCEPROP 2 LAST CDS_LIB pure_quanta
J 0
(-5425 4700);
DISPLAY INVISIBLE (-5425 4700);
FORCEPROP 1 LAST PATH I26
J 0
(-5375 4875);
DISPLAY 0.978723 (-5375 4875);
PAINT WHITE (-5375 4875);
DISPLAY INVISIBLE (-5375 4875);
FORCEPROP 1 LAST PART_NUMBER CS31002JB08
J 0
(-5385 4575);
DISPLAY 0.489362 (-5385 4575);
PAINT SKYBLUE (-5385 4575);
DISPLAY INVISIBLE (-5385 4575);
FORCEADD Q_RES..2
(-6275 5250);
FORCEPROP 1 LAST LOCATION R1443
J 0
(-6230 5375);
DISPLAY 0.489362 (-6230 5375);
PAINT SKYBLUE (-6230 5375);
FORCEPROP 0 LAST $SEC 1
J 0
(-6225 5425);
DISPLAY 0.680851 (-6225 5425);
PAINT MONO (-6225 5425);
DISPLAY INVISIBLE (-6225 5425);
FORCEPROP 0 LAST CDS_SEC 1
J 0
(-6225 5425);
DISPLAY 0.680851 (-6225 5425);
DISPLAY INVISIBLE (-6225 5425);
FORCEPROP 1 LASTPIN (-6275 5350) $PN 1
J 0
(-6270 5312);
DISPLAY 0.489362 (-6270 5312);
PAINT MONO (-6270 5312);
FORCEPROP 1 LASTPIN (-6275 5150) $PN 2
J 0
(-6270 5160);
DISPLAY 0.489362 (-6270 5160);
PAINT MONO (-6270 5160);
FORCEPROP 1 LAST MATERIAL CHIP
J 0
(-6235 5175);
DISPLAY 0.489362 (-6235 5175);
PAINT SKYBLUE (-6235 5175);
FORCEPROP 1 LAST PACK_TYPE 0402LF
J 0
(-6235 5075);
DISPLAY 0.489362 (-6235 5075);
PAINT SKYBLUE (-6235 5075);
FORCEPROP 1 LAST VALUE 16.9K
J 0
(-6230 5325);
DISPLAY 0.489362 (-6230 5325);
PAINT SKYBLUE (-6230 5325);
FORCEPROP 1 LAST TOLERANCE 1%
J 0
(-6230 5275);
DISPLAY 0.489362 (-6230 5275);
PAINT SKYBLUE (-6230 5275);
FORCEPROP 1 LAST WATTAGE 1/16W
J 0
(-6235 5225);
DISPLAY 0.489362 (-6235 5225);
PAINT SKYBLUE (-6235 5225);
FORCEPROP 2 LAST BOM_COST VR_SYSTEM
J 0
(-6225 5425);
DISPLAY 0.680851 (-6225 5425);
DISPLAY INVISIBLE (-6225 5425);
FORCEPROP 2 LAST CDS_LIB pure_quanta
J 0
(-6275 5250);
DISPLAY INVISIBLE (-6275 5250);
FORCEPROP 1 LAST PATH I27
J 0
(-6225 5425);
DISPLAY 0.978723 (-6225 5425);
PAINT WHITE (-6225 5425);
DISPLAY INVISIBLE (-6225 5425);
FORCEPROP 1 LAST PART_NUMBER CS31692FB03
J 0
(-6235 5125);
DISPLAY 0.489362 (-6235 5125);
PAINT SKYBLUE (-6235 5125);
DISPLAY INVISIBLE (-6235 5125);
FORCEADD UNIVERSAL_GND..1
(-6275 5050);
FORCEPROP 3 LASTPIN (-6275 5100) SIG_NAME GND\g
J 0
(-6265 5110);
DISPLAY 0.659574 (-6265 5110);
PAINT MONO (-6265 5110);
DISPLAY INVISIBLE (-6265 5110);
FORCEPROP 2 LAST CDS_LIB pure_quanta_power
J 0
(-6275 5050);
DISPLAY INVISIBLE (-6275 5050);
FORCEPROP 2 LAST BOM_COST VR_SYSTEM
J 0
(-6600 5125);
DISPLAY 0.617021 (-6600 5125);
PAINT PURPLE (-6600 5125);
DISPLAY INVISIBLE (-6600 5125);
FORCEPROP 1 LAST HDL_POWER GND
J 1
(-6250 4975);
DISPLAY 0.872340 (-6250 4975);
PAINT GREEN (-6250 4975);
DISPLAY INVISIBLE (-6250 4975);
FORCEPROP 1 LAST PATH I28
J 0
(-6200 5050);
DISPLAY 0.872340 (-6200 5050);
PAINT AQUA (-6200 5050);
DISPLAY INVISIBLE (-6200 5050);
FORCEADD UNIVERSAL_POWER..1
(-6175 4750);
FORCEPROP 3 LASTPIN (-6175 4700) SIG_NAME P12V_MEM_CPU1\g
J 0
(-6165 4710);
DISPLAY 0.659574 (-6165 4710);
PAINT MONO (-6165 4710);
DISPLAY INVISIBLE (-6165 4710);
FORCEPROP 1 LAST HDL_POWER P12V_MEM_CPU1
J 1
(-6200 4800);
DISPLAY 0.489362 (-6200 4800);
PAINT GREEN (-6200 4800);
FORCEPROP 2 LAST CDS_LIB pure_quanta_power
J 0
(-6175 4750);
DISPLAY INVISIBLE (-6175 4750);
FORCEPROP 2 LAST BOM_COST VR_SYSTEM
J 0
(-6175 4850);
DISPLAY 0.617021 (-6175 4850);
PAINT PURPLE (-6175 4850);
DISPLAY INVISIBLE (-6175 4850);
FORCEPROP 1 LAST PATH I29
J 0
(-6125 4775);
DISPLAY 0.872340 (-6125 4775);
PAINT AQUA (-6125 4775);
DISPLAY INVISIBLE (-6125 4775);
FORCEADD OFFPAGE..1
(-6375 2175);
FORCEPROP 2 LAST $XR0 260 
J 0
(-6627 2175);
DISPLAY 0.638298 (-6627 2175);
PAINT MONO (-6627 2175);
FORCEPROP 2 LAST CDS_LIB standard
J 0
(-6375 2175);
DISPLAY INVISIBLE (-6375 2175);
FORCEPROP 1 LAST OFFPAGE TRUE
J 0
(-6050 2050);
DISPLAY 0.872340 (-6050 2050);
PAINT GREEN (-6050 2050);
DISPLAY INVISIBLE (-6050 2050);
FORCEPROP 1 LAST COMMENT_BODY TRUE
J 0
(-6250 2075);
DISPLAY 0.872340 (-6250 2075);
PAINT GREEN (-6250 2075);
DISPLAY INVISIBLE (-6250 2075);
FORCEPROP 2 LAST PATH I3
J 0
(-6625 2225);
DISPLAY 0.680851 (-6625 2225);
DISPLAY INVISIBLE (-6625 2225);
FORCEADD Q_RES..2
(-6275 5750);
FORCEPROP 1 LAST LOCATION R1442
J 0
(-6230 5875);
DISPLAY 0.489362 (-6230 5875);
PAINT SKYBLUE (-6230 5875);
FORCEPROP 0 LAST $SEC 1
J 0
(-6225 5925);
DISPLAY 0.680851 (-6225 5925);
PAINT MONO (-6225 5925);
DISPLAY INVISIBLE (-6225 5925);
FORCEPROP 0 LAST CDS_SEC 1
J 0
(-6225 5925);
DISPLAY 0.680851 (-6225 5925);
DISPLAY INVISIBLE (-6225 5925);
FORCEPROP 1 LASTPIN (-6275 5850) $PN 1
J 0
(-6270 5812);
DISPLAY 0.489362 (-6270 5812);
PAINT MONO (-6270 5812);
FORCEPROP 1 LASTPIN (-6275 5650) $PN 2
J 0
(-6270 5660);
DISPLAY 0.489362 (-6270 5660);
PAINT MONO (-6270 5660);
FORCEPROP 1 LAST PACK_TYPE 0402LF
J 0
(-6235 5575);
DISPLAY 0.489362 (-6235 5575);
PAINT SKYBLUE (-6235 5575);
FORCEPROP 1 LAST VALUE 100K
J 0
(-6230 5825);
DISPLAY 0.489362 (-6230 5825);
PAINT SKYBLUE (-6230 5825);
FORCEPROP 1 LAST WATTAGE 1/16W
J 0
(-6235 5725);
DISPLAY 0.489362 (-6235 5725);
PAINT SKYBLUE (-6235 5725);
FORCEPROP 1 LAST MATERIAL CHIP
J 0
(-6235 5675);
DISPLAY 0.489362 (-6235 5675);
PAINT SKYBLUE (-6235 5675);
FORCEPROP 1 LAST TOLERANCE 1%
J 0
(-6230 5775);
DISPLAY 0.489362 (-6230 5775);
PAINT SKYBLUE (-6230 5775);
FORCEPROP 2 LAST CDS_LIB pure_quanta
J 0
(-6275 5750);
DISPLAY INVISIBLE (-6275 5750);
FORCEPROP 2 LAST BOM_COST VR_SYSTEM
J 0
(-6225 5925);
DISPLAY 0.680851 (-6225 5925);
DISPLAY INVISIBLE (-6225 5925);
FORCEPROP 1 LAST PATH I30
J 0
(-6225 5925);
DISPLAY 0.978723 (-6225 5925);
PAINT WHITE (-6225 5925);
DISPLAY INVISIBLE (-6225 5925);
FORCEPROP 1 LAST PART_NUMBER CS41002FB09
J 0
(-6235 5625);
DISPLAY 0.489362 (-6235 5625);
PAINT SKYBLUE (-6235 5625);
DISPLAY INVISIBLE (-6235 5625);
FORCEADD UNIVERSAL_POWER..1
(-5425 4950);
FORCEPROP 3 LASTPIN (-5425 4900) SIG_NAME P3V3_AUX\g
J 0
(-5415 4910);
DISPLAY 0.659574 (-5415 4910);
PAINT MONO (-5415 4910);
DISPLAY INVISIBLE (-5415 4910);
FORCEPROP 1 LAST HDL_POWER P3V3_AUX
J 1
(-5425 5000);
DISPLAY 0.489362 (-5425 5000);
PAINT GREEN (-5425 5000);
FORCEPROP 2 LAST CDS_LIB pure_quanta_power
J 0
(-5425 4950);
DISPLAY INVISIBLE (-5425 4950);
FORCEPROP 2 LAST BOM_COST VR_SYSTEM
J 0
(-5425 5050);
DISPLAY 0.617021 (-5425 5050);
PAINT PURPLE (-5425 5050);
DISPLAY INVISIBLE (-5425 5050);
FORCEPROP 1 LAST PATH I31
J 0
(-5375 4975);
DISPLAY 0.872340 (-5375 4975);
PAINT AQUA (-5375 4975);
DISPLAY INVISIBLE (-5375 4975);
FORCEADD UNIVERSAL_GND..1
R 7
(-5425 5525);
FORCEPROP 3 LASTPIN (-5375 5525) SIG_NAME GND\g
J 0
(-5365 5535);
DISPLAY 0.659574 (-5365 5535);
PAINT MONO (-5365 5535);
DISPLAY INVISIBLE (-5365 5535);
FORCEPROP 2 LAST CDS_LIB pure_quanta_power
J 2
(-5425 5525);
DISPLAY INVISIBLE (-5425 5525);
FORCEPROP 2 LAST BOM_COST VR_SYSTEM
R 1
J 0
(-5350 5200);
DISPLAY 0.617021 (-5350 5200);
PAINT PURPLE (-5350 5200);
DISPLAY INVISIBLE (-5350 5200);
FORCEPROP 1 LAST HDL_POWER GND
R 1
J 1
(-5500 5550);
DISPLAY 0.872340 (-5500 5550);
PAINT GREEN (-5500 5550);
DISPLAY INVISIBLE (-5500 5550);
FORCEPROP 1 LAST PATH I32
R 1
J 0
(-5425 5600);
DISPLAY 0.872340 (-5425 5600);
PAINT AQUA (-5425 5600);
DISPLAY INVISIBLE (-5425 5600);
FORCEADD BSS138DW7F..1
(-4800 4150);
FORCEPROP 1 LAST LOCATION Q19
J 0
(-4950 4355);
DISPLAY 0.489362 (-4950 4355);
PAINT SKYBLUE (-4950 4355);
FORCEPROP 0 LAST $SEC 1
J 0
(-4925 4500);
DISPLAY 0.680851 (-4925 4500);
PAINT MONO (-4925 4500);
DISPLAY INVISIBLE (-4925 4500);
FORCEPROP 0 LAST CDS_SEC 1
J 0
(-4925 4500);
DISPLAY 0.680851 (-4925 4500);
DISPLAY INVISIBLE (-4925 4500);
FORCEPROP 0 LASTPIN (-5100 4100) $PN 6
J 2
(-5110 4110);
DISPLAY 0.489362 (-5110 4110);
PAINT MONO (-5110 4110);
FORCEPROP 0 LASTPIN (-4500 4100) $PN 3
J 0
(-4490 4110);
DISPLAY 0.489362 (-4490 4110);
PAINT MONO (-4490 4110);
FORCEPROP 0 LASTPIN (-5100 4150) $PN 2
J 2
(-5110 4160);
DISPLAY 0.489362 (-5110 4160);
PAINT MONO (-5110 4160);
FORCEPROP 0 LASTPIN (-4500 4150) $PN 5
J 0
(-4490 4160);
DISPLAY 0.489362 (-4490 4160);
PAINT MONO (-4490 4160);
FORCEPROP 0 LASTPIN (-5100 4200) $PN 1
J 2
(-5110 4210);
DISPLAY 0.489362 (-5110 4210);
PAINT MONO (-5110 4210);
FORCEPROP 0 LASTPIN (-4500 4200) $PN 4
J 0
(-4490 4210);
DISPLAY 0.489362 (-4490 4210);
PAINT MONO (-4490 4210);
FORCEPROP 2 LAST VALUE BSS138DW-7-F
J 0
(-4925 4400);
DISPLAY 0.489362 (-4925 4400);
PAINT SKYBLUE (-4925 4400);
FORCEPROP 2 LAST PART_TYPE SMLF
J 0
(-4925 4450);
DISPLAY 0.680851 (-4925 4450);
FORCEPROP 1 LAST MATERIAL IC
J 0
(-4950 4260);
DISPLAY 0.489362 (-4950 4260);
PAINT SKYBLUE (-4950 4260);
FORCEPROP 1 LAST NEEDS_NO_SIZE TRUE
J 0
(-4800 4150);
DISPLAY 0.468085 (-4800 4150);
PAINT GREEN (-4800 4150);
DISPLAY INVISIBLE (-4800 4150);
FORCEPROP 2 LAST CDS_LIB pure_quanta
J 0
(-4800 4150);
DISPLAY INVISIBLE (-4800 4150);
FORCEPROP 1 LAST PATH I33
J 0
(-4675 4255);
DISPLAY 0.723404 (-4675 4255);
PAINT GREEN (-4675 4255);
DISPLAY INVISIBLE (-4675 4255);
FORCEPROP 1 LAST PART_NUMBER BAM01380032
J 0
(-4950 4310);
DISPLAY 0.489362 (-4950 4310);
PAINT SKYBLUE (-4950 4310);
DISPLAY INVISIBLE (-4950 4310);
FORCEADD UNIVERSAL_GND..1
R 7
(-5175 4200);
FORCEPROP 3 LASTPIN (-5125 4200) SIG_NAME GND\g
J 0
(-5115 4210);
DISPLAY 0.659574 (-5115 4210);
PAINT MONO (-5115 4210);
DISPLAY INVISIBLE (-5115 4210);
FORCEPROP 2 LAST CDS_LIB pure_quanta_power
J 0
(-5175 4200);
DISPLAY INVISIBLE (-5175 4200);
FORCEPROP 2 LAST BOM_COST VR_SYSTEM
R 1
J 0
(-5100 3875);
DISPLAY 0.617021 (-5100 3875);
PAINT PURPLE (-5100 3875);
DISPLAY INVISIBLE (-5100 3875);
FORCEPROP 1 LAST HDL_POWER GND
R 1
J 1
(-5250 4225);
DISPLAY 0.872340 (-5250 4225);
PAINT GREEN (-5250 4225);
DISPLAY INVISIBLE (-5250 4225);
FORCEPROP 1 LAST PATH I34
R 1
J 0
(-5175 4275);
DISPLAY 0.872340 (-5175 4275);
PAINT AQUA (-5175 4275);
DISPLAY INVISIBLE (-5175 4275);
FORCEADD UNIVERSAL_GND..1
R 1
(-4425 4200);
FORCEPROP 3 LASTPIN (-4475 4200) SIG_NAME GND\g
J 0
(-4465 4210);
DISPLAY 0.659574 (-4465 4210);
PAINT MONO (-4465 4210);
DISPLAY INVISIBLE (-4465 4210);
FORCEPROP 2 LAST CDS_LIB pure_quanta_power
J 0
(-4425 4200);
DISPLAY INVISIBLE (-4425 4200);
FORCEPROP 2 LAST BOM_COST VR_SYSTEM
R 1
J 0
(-4500 3875);
DISPLAY 0.617021 (-4500 3875);
PAINT PURPLE (-4500 3875);
DISPLAY INVISIBLE (-4500 3875);
FORCEPROP 1 LAST HDL_POWER GND
R 1
J 1
(-4350 4225);
DISPLAY 0.872340 (-4350 4225);
PAINT GREEN (-4350 4225);
DISPLAY INVISIBLE (-4350 4225);
FORCEPROP 1 LAST PATH I35
R 1
J 0
(-4425 4275);
DISPLAY 0.872340 (-4425 4275);
PAINT AQUA (-4425 4275);
DISPLAY INVISIBLE (-4425 4275);
FORCEADD BSS138DW7F..1
(-5050 5475);
FORCEPROP 1 LAST LOCATION Q18
J 0
(-5200 5680);
DISPLAY 0.489362 (-5200 5680);
PAINT SKYBLUE (-5200 5680);
FORCEPROP 0 LAST $SEC 1
J 0
(-5175 5825);
DISPLAY 0.680851 (-5175 5825);
PAINT MONO (-5175 5825);
DISPLAY INVISIBLE (-5175 5825);
FORCEPROP 0 LAST CDS_SEC 1
J 0
(-5175 5825);
DISPLAY 0.680851 (-5175 5825);
DISPLAY INVISIBLE (-5175 5825);
FORCEPROP 0 LASTPIN (-5350 5425) $PN 6
J 2
(-5360 5435);
DISPLAY 0.489362 (-5360 5435);
PAINT MONO (-5360 5435);
FORCEPROP 0 LASTPIN (-4750 5425) $PN 3
J 0
(-4740 5435);
DISPLAY 0.489362 (-4740 5435);
PAINT MONO (-4740 5435);
FORCEPROP 0 LASTPIN (-5350 5475) $PN 2
J 2
(-5360 5485);
DISPLAY 0.489362 (-5360 5485);
PAINT MONO (-5360 5485);
FORCEPROP 0 LASTPIN (-4750 5475) $PN 5
J 0
(-4740 5485);
DISPLAY 0.489362 (-4740 5485);
PAINT MONO (-4740 5485);
FORCEPROP 0 LASTPIN (-5350 5525) $PN 1
J 2
(-5360 5535);
DISPLAY 0.489362 (-5360 5535);
PAINT MONO (-5360 5535);
FORCEPROP 0 LASTPIN (-4750 5525) $PN 4
J 0
(-4740 5535);
DISPLAY 0.489362 (-4740 5535);
PAINT MONO (-4740 5535);
FORCEPROP 1 LAST MATERIAL IC
J 0
(-5200 5585);
DISPLAY 0.489362 (-5200 5585);
PAINT SKYBLUE (-5200 5585);
FORCEPROP 2 LAST VALUE BSS138DW-7-F
J 0
(-5175 5725);
DISPLAY 0.489362 (-5175 5725);
PAINT SKYBLUE (-5175 5725);
FORCEPROP 2 LAST PART_TYPE SMLF
J 0
(-5175 5775);
DISPLAY 0.680851 (-5175 5775);
FORCEPROP 1 LAST NEEDS_NO_SIZE TRUE
J 0
(-5050 5475);
DISPLAY 0.468085 (-5050 5475);
PAINT GREEN (-5050 5475);
DISPLAY INVISIBLE (-5050 5475);
FORCEPROP 2 LAST CDS_LIB pure_quanta
J 0
(-5050 5475);
DISPLAY INVISIBLE (-5050 5475);
FORCEPROP 1 LAST PATH I36
J 0
(-4925 5580);
DISPLAY 0.723404 (-4925 5580);
PAINT GREEN (-4925 5580);
DISPLAY INVISIBLE (-4925 5580);
FORCEPROP 1 LAST PART_NUMBER BAM01380032
J 0
(-5200 5635);
DISPLAY 0.489362 (-5200 5635);
PAINT SKYBLUE (-5200 5635);
DISPLAY INVISIBLE (-5200 5635);
FORCEADD UNIVERSAL_GND..1
R 1
(-4675 5525);
FORCEPROP 3 LASTPIN (-4725 5525) SIG_NAME GND\g
J 0
(-4715 5535);
DISPLAY 0.659574 (-4715 5535);
PAINT MONO (-4715 5535);
DISPLAY INVISIBLE (-4715 5535);
FORCEPROP 2 LAST BOM_COST VR_SYSTEM
R 1
J 0
(-4750 5200);
DISPLAY 0.617021 (-4750 5200);
PAINT PURPLE (-4750 5200);
DISPLAY INVISIBLE (-4750 5200);
FORCEPROP 2 LAST CDS_LIB pure_quanta_power
R 1
J 0
(-4675 5525);
DISPLAY INVISIBLE (-4675 5525);
FORCEPROP 1 LAST HDL_POWER GND
R 1
J 1
(-4600 5550);
DISPLAY 0.872340 (-4600 5550);
PAINT GREEN (-4600 5550);
DISPLAY INVISIBLE (-4600 5550);
FORCEPROP 1 LAST PATH I37
R 1
J 0
(-4675 5600);
DISPLAY 0.872340 (-4675 5600);
PAINT AQUA (-4675 5600);
DISPLAY INVISIBLE (-4675 5600);
FORCEADD UNIVERSAL_POWER..1
(-6275 6075);
FORCEPROP 3 LASTPIN (-6275 6025) SIG_NAME P12V_MEM_CPU0\g
J 0
(-6265 6035);
DISPLAY 0.659574 (-6265 6035);
PAINT MONO (-6265 6035);
DISPLAY INVISIBLE (-6265 6035);
FORCEPROP 1 LAST HDL_POWER P12V_MEM_CPU0
J 1
(-6300 6125);
DISPLAY 0.489362 (-6300 6125);
PAINT GREEN (-6300 6125);
FORCEPROP 2 LAST CDS_LIB pure_quanta_power
J 0
(-6275 6075);
DISPLAY INVISIBLE (-6275 6075);
FORCEPROP 2 LAST BOM_COST VR_SYSTEM
J 0
(-6275 6175);
DISPLAY 0.617021 (-6275 6175);
PAINT PURPLE (-6275 6175);
DISPLAY INVISIBLE (-6275 6175);
FORCEPROP 1 LAST PATH I38
J 0
(-6225 6100);
DISPLAY 0.872340 (-6225 6100);
PAINT AQUA (-6225 6100);
DISPLAY INVISIBLE (-6225 6100);
FORCEADD Q_RES..2
(-5500 5975);
FORCEPROP 1 LAST LOCATION R1450
J 0
(-5455 6100);
DISPLAY 0.489362 (-5455 6100);
PAINT SKYBLUE (-5455 6100);
FORCEPROP 0 LAST $SEC 1
J 0
(-5450 6150);
DISPLAY 0.680851 (-5450 6150);
PAINT MONO (-5450 6150);
DISPLAY INVISIBLE (-5450 6150);
FORCEPROP 0 LAST CDS_SEC 1
J 0
(-5450 6150);
DISPLAY 0.680851 (-5450 6150);
DISPLAY INVISIBLE (-5450 6150);
FORCEPROP 1 LASTPIN (-5500 6075) $PN 1
J 0
(-5495 6037);
DISPLAY 0.489362 (-5495 6037);
PAINT MONO (-5495 6037);
FORCEPROP 1 LASTPIN (-5500 5875) $PN 2
J 0
(-5495 5885);
DISPLAY 0.489362 (-5495 5885);
PAINT MONO (-5495 5885);
FORCEPROP 1 LAST TOLERANCE 5%
J 0
(-5455 6000);
DISPLAY 0.489362 (-5455 6000);
PAINT SKYBLUE (-5455 6000);
FORCEPROP 1 LAST VALUE 10K
J 0
(-5455 6050);
DISPLAY 0.489362 (-5455 6050);
PAINT SKYBLUE (-5455 6050);
FORCEPROP 1 LAST WATTAGE 1/16W
J 0
(-5460 5950);
DISPLAY 0.489362 (-5460 5950);
PAINT SKYBLUE (-5460 5950);
FORCEPROP 1 LAST MATERIAL CHIP
J 0
(-5460 5900);
DISPLAY 0.489362 (-5460 5900);
PAINT SKYBLUE (-5460 5900);
FORCEPROP 1 LAST PACK_TYPE 0402LF
J 0
(-5460 5800);
DISPLAY 0.489362 (-5460 5800);
PAINT SKYBLUE (-5460 5800);
FORCEPROP 2 LAST BOM_COST VR_SYSTEM
J 0
(-5450 6150);
DISPLAY 0.680851 (-5450 6150);
DISPLAY INVISIBLE (-5450 6150);
FORCEPROP 2 LAST CDS_LIB pure_quanta
J 0
(-5500 5975);
DISPLAY INVISIBLE (-5500 5975);
FORCEPROP 1 LAST PATH I39
J 0
(-5450 6150);
DISPLAY 0.978723 (-5450 6150);
PAINT WHITE (-5450 6150);
DISPLAY INVISIBLE (-5450 6150);
FORCEPROP 1 LAST PART_NUMBER CS31002JB08
J 0
(-5460 5850);
DISPLAY 0.489362 (-5460 5850);
PAINT SKYBLUE (-5460 5850);
DISPLAY INVISIBLE (-5460 5850);
FORCEADD UNIVERSAL_POWER..1
(-5500 6300);
FORCEPROP 3 LASTPIN (-5500 6250) SIG_NAME P3V3_AUX\g
J 0
(-5490 6260);
DISPLAY 0.659574 (-5490 6260);
PAINT MONO (-5490 6260);
DISPLAY INVISIBLE (-5490 6260);
FORCEPROP 1 LAST HDL_POWER P3V3_AUX
J 1
(-5500 6350);
DISPLAY 0.489362 (-5500 6350);
PAINT GREEN (-5500 6350);
FORCEPROP 2 LAST CDS_LIB pure_quanta_power
J 0
(-5500 6300);
DISPLAY INVISIBLE (-5500 6300);
FORCEPROP 2 LAST BOM_COST VR_SYSTEM
J 0
(-5500 6400);
DISPLAY 0.617021 (-5500 6400);
PAINT PURPLE (-5500 6400);
DISPLAY INVISIBLE (-5500 6400);
FORCEPROP 1 LAST PATH I40
J 0
(-5450 6325);
DISPLAY 0.872340 (-5450 6325);
PAINT AQUA (-5450 6325);
DISPLAY INVISIBLE (-5450 6325);
FORCEADD Q_RES..2
(-4425 5950);
FORCEPROP 1 LAST LOCATION R1457
J 0
(-4380 6075);
DISPLAY 0.489362 (-4380 6075);
PAINT SKYBLUE (-4380 6075);
FORCEPROP 0 LAST $SEC 1
J 0
(-4375 6125);
DISPLAY 0.680851 (-4375 6125);
PAINT MONO (-4375 6125);
DISPLAY INVISIBLE (-4375 6125);
FORCEPROP 0 LAST CDS_SEC 1
J 0
(-4375 6125);
DISPLAY 0.680851 (-4375 6125);
DISPLAY INVISIBLE (-4375 6125);
FORCEPROP 1 LASTPIN (-4425 6050) $PN 1
J 0
(-4420 6012);
DISPLAY 0.489362 (-4420 6012);
PAINT MONO (-4420 6012);
FORCEPROP 1 LASTPIN (-4425 5850) $PN 2
J 0
(-4420 5860);
DISPLAY 0.489362 (-4420 5860);
PAINT MONO (-4420 5860);
FORCEPROP 1 LAST WATTAGE 1/16W
J 0
(-4385 5925);
DISPLAY 0.489362 (-4385 5925);
PAINT SKYBLUE (-4385 5925);
FORCEPROP 1 LAST MATERIAL CHIP
J 0
(-4385 5875);
DISPLAY 0.489362 (-4385 5875);
PAINT SKYBLUE (-4385 5875);
FORCEPROP 1 LAST TOLERANCE 5%
J 0
(-4380 5975);
DISPLAY 0.489362 (-4380 5975);
PAINT SKYBLUE (-4380 5975);
FORCEPROP 1 LAST VALUE 10K
J 0
(-4380 6025);
DISPLAY 0.489362 (-4380 6025);
PAINT SKYBLUE (-4380 6025);
FORCEPROP 1 LAST PACK_TYPE 0402LF
J 0
(-4385 5775);
DISPLAY 0.489362 (-4385 5775);
PAINT SKYBLUE (-4385 5775);
FORCEPROP 2 LAST CDS_LIB pure_quanta
J 0
(-4425 5950);
DISPLAY INVISIBLE (-4425 5950);
FORCEPROP 2 LAST BOM_COST VR_SYSTEM
J 0
(-4375 6125);
DISPLAY 0.680851 (-4375 6125);
DISPLAY INVISIBLE (-4375 6125);
FORCEPROP 1 LAST PATH I41
J 0
(-4375 6125);
DISPLAY 0.978723 (-4375 6125);
PAINT WHITE (-4375 6125);
DISPLAY INVISIBLE (-4375 6125);
FORCEPROP 1 LAST PART_NUMBER CS31002JB08
J 0
(-4385 5825);
DISPLAY 0.489362 (-4385 5825);
PAINT SKYBLUE (-4385 5825);
DISPLAY INVISIBLE (-4385 5825);
FORCEADD P1V0_AUX..1
(-4425 6225);
FORCEPROP 3 LASTPIN (-4425 6175) SIG_NAME P1V8_AUX\g
J 0
(-4415 6185);
DISPLAY 0.659574 (-4415 6185);
PAINT MONO (-4415 6185);
DISPLAY INVISIBLE (-4415 6185);
FORCEPROP 1 LAST HDL_POWER P1V8_AUX
J 1
(-4415 6265);
DISPLAY 0.489362 (-4415 6265);
PAINT GREEN (-4415 6265);
FORCEPROP 2 LAST CDS_LIB pure_quanta_power
J 0
(-4425 6225);
DISPLAY INVISIBLE (-4425 6225);
FORCEPROP 1 LAST PATH I42
J 0
(-4375 6250);
DISPLAY 0.872340 (-4375 6250);
PAINT AQUA (-4375 6250);
DISPLAY INVISIBLE (-4375 6250);
FORCEADD Q_RES..2
(-4325 4650);
FORCEPROP 1 LAST LOCATION R1452
J 0
(-4280 4775);
DISPLAY 0.489362 (-4280 4775);
PAINT SKYBLUE (-4280 4775);
FORCEPROP 0 LAST $SEC 1
J 0
(-4275 4825);
DISPLAY 0.680851 (-4275 4825);
PAINT MONO (-4275 4825);
DISPLAY INVISIBLE (-4275 4825);
FORCEPROP 0 LAST CDS_SEC 1
J 0
(-4275 4825);
DISPLAY 0.680851 (-4275 4825);
DISPLAY INVISIBLE (-4275 4825);
FORCEPROP 1 LASTPIN (-4325 4750) $PN 1
J 0
(-4320 4712);
DISPLAY 0.489362 (-4320 4712);
PAINT MONO (-4320 4712);
FORCEPROP 1 LASTPIN (-4325 4550) $PN 2
J 0
(-4320 4560);
DISPLAY 0.489362 (-4320 4560);
PAINT MONO (-4320 4560);
FORCEPROP 1 LAST WATTAGE 1/16W
J 0
(-4285 4625);
DISPLAY 0.489362 (-4285 4625);
PAINT SKYBLUE (-4285 4625);
FORCEPROP 1 LAST MATERIAL CHIP
J 0
(-4285 4575);
DISPLAY 0.489362 (-4285 4575);
PAINT SKYBLUE (-4285 4575);
FORCEPROP 1 LAST PACK_TYPE 0402LF
J 0
(-4285 4475);
DISPLAY 0.489362 (-4285 4475);
PAINT SKYBLUE (-4285 4475);
FORCEPROP 1 LAST TOLERANCE 5%
J 0
(-4280 4675);
DISPLAY 0.489362 (-4280 4675);
PAINT SKYBLUE (-4280 4675);
FORCEPROP 1 LAST VALUE 10K
J 0
(-4280 4725);
DISPLAY 0.489362 (-4280 4725);
PAINT SKYBLUE (-4280 4725);
FORCEPROP 2 LAST BOM_COST VR_SYSTEM
J 0
(-4275 4825);
DISPLAY 0.680851 (-4275 4825);
DISPLAY INVISIBLE (-4275 4825);
FORCEPROP 2 LAST CDS_LIB pure_quanta
J 0
(-4325 4650);
DISPLAY INVISIBLE (-4325 4650);
FORCEPROP 1 LAST PATH I43
J 0
(-4275 4825);
DISPLAY 0.978723 (-4275 4825);
PAINT WHITE (-4275 4825);
DISPLAY INVISIBLE (-4275 4825);
FORCEPROP 1 LAST PART_NUMBER CS31002JB08
J 0
(-4285 4525);
DISPLAY 0.489362 (-4285 4525);
PAINT SKYBLUE (-4285 4525);
DISPLAY INVISIBLE (-4285 4525);
FORCEADD OFFPAGE..2
(-3700 4375);
FORCEPROP 2 LAST $XR0 260 
J 0
(-3511 4375);
DISPLAY 0.638298 (-3511 4375);
PAINT MONO (-3511 4375);
FORCEPROP 2 LAST CDS_LIB standard
J 0
(-3700 4375);
DISPLAY INVISIBLE (-3700 4375);
FORCEPROP 1 LAST OFFPAGE TRUE
J 0
(-3375 4250);
DISPLAY 0.872340 (-3375 4250);
PAINT GREEN (-3375 4250);
DISPLAY INVISIBLE (-3375 4250);
FORCEPROP 1 LAST COMMENT_BODY TRUE
J 0
(-3745 4280);
DISPLAY 0.872340 (-3745 4280);
PAINT GREEN (-3745 4280);
DISPLAY INVISIBLE (-3745 4280);
FORCEPROP 2 LAST PATH I44
J 0
(-3500 4425);
DISPLAY 0.680851 (-3500 4425);
DISPLAY INVISIBLE (-3500 4425);
FORCEADD P1V0_AUX..1
(-4325 4925);
FORCEPROP 3 LASTPIN (-4325 4875) SIG_NAME P1V8_AUX\g
J 0
(-4315 4885);
DISPLAY 0.659574 (-4315 4885);
PAINT MONO (-4315 4885);
DISPLAY INVISIBLE (-4315 4885);
FORCEPROP 1 LAST HDL_POWER P1V8_AUX
J 1
(-4315 4965);
DISPLAY 0.489362 (-4315 4965);
PAINT GREEN (-4315 4965);
FORCEPROP 2 LAST CDS_LIB pure_quanta_power
J 0
(-4325 4925);
DISPLAY INVISIBLE (-4325 4925);
FORCEPROP 1 LAST PATH I45
J 0
(-4275 4950);
DISPLAY 0.872340 (-4275 4950);
PAINT AQUA (-4275 4950);
DISPLAY INVISIBLE (-4275 4950);
FORCEADD OFFPAGE..2
(-3900 5625);
FORCEPROP 2 LAST $XR0 260 
J 0
(-3711 5625);
DISPLAY 0.638298 (-3711 5625);
PAINT MONO (-3711 5625);
FORCEPROP 2 LAST CDS_LIB standard
J 0
(-3900 5625);
DISPLAY INVISIBLE (-3900 5625);
FORCEPROP 1 LAST OFFPAGE TRUE
J 0
(-3575 5500);
DISPLAY 0.872340 (-3575 5500);
PAINT GREEN (-3575 5500);
DISPLAY INVISIBLE (-3575 5500);
FORCEPROP 1 LAST COMMENT_BODY TRUE
J 0
(-3945 5530);
DISPLAY 0.872340 (-3945 5530);
PAINT GREEN (-3945 5530);
DISPLAY INVISIBLE (-3945 5530);
FORCEPROP 2 LAST PATH I46
J 0
(-3700 5675);
DISPLAY 0.680851 (-3700 5675);
DISPLAY INVISIBLE (-3700 5675);
FORCEADD Q_CAP..1
R 2
(-3750 2350);
FORCEPROP 1 LAST LOCATION C347
J 0
(-3675 2475);
DISPLAY 0.489362 (-3675 2475);
PAINT SKYBLUE (-3675 2475);
FORCEPROP 0 LAST $SEC 1
J 0
(-3675 2500);
DISPLAY 0.680851 (-3675 2500);
PAINT MONO (-3675 2500);
DISPLAY INVISIBLE (-3675 2500);
FORCEPROP 0 LAST CDS_SEC 1
J 0
(-3675 2500);
DISPLAY 0.680851 (-3675 2500);
DISPLAY INVISIBLE (-3675 2500);
FORCEPROP 1 LASTPIN (-3750 2450) $PN 1
J 2
(-3760 2430);
DISPLAY 0.489362 (-3760 2430);
PAINT MONO (-3760 2430);
FORCEPROP 1 LASTPIN (-3750 2250) $PN 2
J 2
(-3760 2230);
DISPLAY 0.489362 (-3760 2230);
PAINT MONO (-3760 2230);
FORCEPROP 1 LAST VALUE 0.1UF
J 0
(-3675 2425);
DISPLAY 0.489362 (-3675 2425);
PAINT SKYBLUE (-3675 2425);
FORCEPROP 1 LAST PACK_TYPE 0402
J 0
(-3675 2175);
DISPLAY 0.489362 (-3675 2175);
PAINT SKYBLUE (-3675 2175);
FORCEPROP 1 LAST MATERIAL X7R
J 0
(-3675 2275);
DISPLAY 0.489362 (-3675 2275);
PAINT SKYBLUE (-3675 2275);
FORCEPROP 1 LAST TOLERANCE 10%
J 0
(-3675 2325);
DISPLAY 0.489362 (-3675 2325);
PAINT SKYBLUE (-3675 2325);
FORCEPROP 1 LAST VOLTAGE 25V
J 0
(-3675 2375);
DISPLAY 0.489362 (-3675 2375);
PAINT SKYBLUE (-3675 2375);
FORCEPROP 2 LAST CDS_LIB pure_quanta
J 2
(-3750 2350);
DISPLAY INVISIBLE (-3750 2350);
FORCEPROP 1 LAST PATH I47
J 2
(-3800 2500);
DISPLAY 0.978723 (-3800 2500);
PAINT WHITE (-3800 2500);
DISPLAY INVISIBLE (-3800 2500);
FORCEPROP 1 LAST PART_NUMBER CH4104K1B00
J 0
(-3675 2225);
DISPLAY 0.489362 (-3675 2225);
PAINT SKYBLUE (-3675 2225);
DISPLAY INVISIBLE (-3675 2225);
FORCEADD P1V0_AUX..1
(-4000 2600);
FORCEPROP 3 LASTPIN (-4000 2550) SIG_NAME P1V8_AUX\g
J 0
(-3990 2560);
DISPLAY 0.659574 (-3990 2560);
PAINT MONO (-3990 2560);
DISPLAY INVISIBLE (-3990 2560);
FORCEPROP 1 LAST HDL_POWER P1V8_AUX
J 1
(-3990 2640);
DISPLAY 0.489362 (-3990 2640);
PAINT GREEN (-3990 2640);
FORCEPROP 2 LAST CDS_LIB pure_quanta_power
J 0
(-4000 2600);
DISPLAY INVISIBLE (-4000 2600);
FORCEPROP 1 LAST PATH I48
J 0
(-3950 2625);
DISPLAY 0.872340 (-3950 2625);
PAINT AQUA (-3950 2625);
DISPLAY INVISIBLE (-3950 2625);
FORCEADD Q_CAP..1
(-3225 1775);
FORCEPROP 1 LAST LOCATION C5014
J 0
(-3175 1875);
DISPLAY 0.978723 (-3175 1875);
FORCEPROP 0 LAST $SEC 1
J 0
(-3175 1925);
DISPLAY 0.680851 (-3175 1925);
PAINT MONO (-3175 1925);
DISPLAY INVISIBLE (-3175 1925);
FORCEPROP 0 LAST CDS_SEC 1
J 0
(-3175 1925);
DISPLAY 0.680851 (-3175 1925);
DISPLAY INVISIBLE (-3175 1925);
FORCEPROP 1 LASTPIN (-3225 1875) $PN 1
J 0
(-3215 1855);
DISPLAY 0.787234 (-3215 1855);
PAINT MONO (-3215 1855);
FORCEPROP 1 LASTPIN (-3225 1675) $PN 2
J 0
(-3215 1655);
DISPLAY 0.787234 (-3215 1655);
PAINT MONO (-3215 1655);
FORCEPROP 1 LAST MATERIAL X7R
J 0
(-3175 1675);
DISPLAY 0.978723 (-3175 1675);
FORCEPROP 1 LAST VALUE 1000PF
J 0
(-3175 1825);
DISPLAY 0.978723 (-3175 1825);
FORCEPROP 1 LAST PACK_TYPE 0402
J 0
(-3175 1575);
DISPLAY 0.978723 (-3175 1575);
FORCEPROP 1 LAST VOLTAGE 50V
J 0
(-3175 1775);
DISPLAY 0.978723 (-3175 1775);
FORCEPROP 1 LAST TOLERANCE 5%
J 0
(-3175 1725);
DISPLAY 0.978723 (-3175 1725);
FORCEPROP 2 LAST CDS_LIB pure_quanta
J 0
(-3225 1775);
DISPLAY INVISIBLE (-3225 1775);
FORCEPROP 1 LAST PATH I49
J 0
(-3175 1925);
DISPLAY 0.978723 (-3175 1925);
PAINT WHITE (-3175 1925);
DISPLAY INVISIBLE (-3175 1925);
FORCEPROP 1 LAST PART_NUMBER TMP_QCH21006JB10
J 0
(-3175 1625);
DISPLAY 0.978723 (-3175 1625);
DISPLAY INVISIBLE (-3175 1625);
FORCEADD Q_RES..1
(-5475 2075);
FORCEPROP 1 LAST LOCATION R1459
J 0
(-5725 2075);
DISPLAY 0.489362 (-5725 2075);
PAINT SKYBLUE (-5725 2075);
FORCEPROP 0 LAST $SEC 1
J 0
(-5575 2125);
DISPLAY 0.680851 (-5575 2125);
PAINT MONO (-5575 2125);
DISPLAY INVISIBLE (-5575 2125);
FORCEPROP 0 LAST CDS_SEC 1
J 0
(-5575 2125);
DISPLAY 0.680851 (-5575 2125);
DISPLAY INVISIBLE (-5575 2125);
FORCEPROP 1 LASTPIN (-5575 2075) $PN 1
J 0
(-5563 2087);
DISPLAY 0.489362 (-5563 2087);
PAINT MONO (-5563 2087);
FORCEPROP 1 LASTPIN (-5375 2075) $PN 2
J 0
(-5413 2087);
DISPLAY 0.489362 (-5413 2087);
PAINT MONO (-5413 2087);
FORCEPROP 1 LAST VALUE 33
J 2
(-5350 2075);
DISPLAY 0.489362 (-5350 2075);
PAINT SKYBLUE (-5350 2075);
FORCEPROP 1 LAST PACK_TYPE 0402LF
J 0
(-5400 2025);
DISPLAY 0.489362 (-5400 2025);
PAINT SKYBLUE (-5400 2025);
DISPLAY INVISIBLE (-5400 2025);
FORCEPROP 1 LAST TOLERANCE 5%
J 0
(-5475 2025);
DISPLAY 0.489362 (-5475 2025);
PAINT SKYBLUE (-5475 2025);
DISPLAY INVISIBLE (-5475 2025);
FORCEPROP 1 LAST MATERIAL CHIP
J 0
(-5325 2075);
DISPLAY 0.489362 (-5325 2075);
PAINT SKYBLUE (-5325 2075);
DISPLAY INVISIBLE (-5325 2075);
FORCEPROP 1 LAST WATTAGE 1/16W
J 2
(-5500 1975);
DISPLAY 0.489362 (-5500 1975);
PAINT SKYBLUE (-5500 1975);
DISPLAY INVISIBLE (-5500 1975);
FORCEPROP 2 LAST BOM_COST OCP3.0 
J 0
(-5400 2175);
DISPLAY 0.680851 (-5400 2175);
DISPLAY INVISIBLE (-5400 2175);
FORCEPROP 2 LAST CDS_LIB pure_quanta
J 0
(-5475 2075);
DISPLAY INVISIBLE (-5475 2075);
FORCEPROP 1 LAST PATH I5
J 0
(-5525 2225);
DISPLAY 0.978723 (-5525 2225);
PAINT WHITE (-5525 2225);
DISPLAY INVISIBLE (-5525 2225);
FORCEPROP 1 LAST PART_NUMBER CS03302JB10
J 0
(-5400 2125);
DISPLAY 0.489362 (-5400 2125);
PAINT SKYBLUE (-5400 2125);
DISPLAY INVISIBLE (-5400 2125);
FORCEADD UNIVERSAL_GND..1
(-3225 1525);
FORCEPROP 3 LASTPIN (-3225 1575) SIG_NAME GND\g
J 0
(-3215 1585);
DISPLAY 0.659574 (-3215 1585);
PAINT MONO (-3215 1585);
DISPLAY INVISIBLE (-3215 1585);
FORCEPROP 2 LAST BOM_COST VR_SYSTEM
J 0
(-3550 1600);
DISPLAY 0.617021 (-3550 1600);
PAINT PURPLE (-3550 1600);
DISPLAY INVISIBLE (-3550 1600);
FORCEPROP 2 LAST CDS_LIB pure_quanta_power
J 0
(-3225 1525);
DISPLAY INVISIBLE (-3225 1525);
FORCEPROP 1 LAST HDL_POWER GND
J 1
(-3200 1450);
DISPLAY 0.872340 (-3200 1450);
PAINT GREEN (-3200 1450);
DISPLAY INVISIBLE (-3200 1450);
FORCEPROP 1 LAST PATH I50
J 0
(-3150 1525);
DISPLAY 0.872340 (-3150 1525);
PAINT AQUA (-3150 1525);
DISPLAY INVISIBLE (-3150 1525);
FORCEADD Q_RES..2
R 2
(-6800 2225);
FORCEPROP 1 LAST LOCATION R6504
J 2
(-6845 2350);
DISPLAY 0.638298 (-6845 2350);
FORCEPROP 0 LAST $SEC 1
J 0
(-6825 2400);
DISPLAY 0.680851 (-6825 2400);
PAINT MONO (-6825 2400);
DISPLAY INVISIBLE (-6825 2400);
FORCEPROP 0 LAST CDS_SEC 1
J 0
(-6825 2400);
DISPLAY 0.680851 (-6825 2400);
DISPLAY INVISIBLE (-6825 2400);
FORCEPROP 1 LASTPIN (-6800 2325) $PN 1
J 2
(-6805 2287);
DISPLAY 0.787234 (-6805 2287);
PAINT MONO (-6805 2287);
FORCEPROP 1 LASTPIN (-6800 2125) $PN 2
J 2
(-6805 2135);
DISPLAY 0.787234 (-6805 2135);
PAINT MONO (-6805 2135);
FORCEPROP 1 LAST TOLERANCE 1%
J 2
(-6845 2250);
DISPLAY 0.638298 (-6845 2250);
FORCEPROP 1 LAST PACK_TYPE 0402LF
J 2
(-6840 2050);
DISPLAY 0.638298 (-6840 2050);
FORCEPROP 1 LAST WATTAGE 1/16W
J 2
(-6840 2200);
DISPLAY 0.638298 (-6840 2200);
FORCEPROP 1 LAST MATERIAL CHIP
J 2
(-6840 2150);
DISPLAY 0.638298 (-6840 2150);
FORCEPROP 1 LAST VALUE 10K
J 2
(-6845 2300);
DISPLAY 0.638298 (-6845 2300);
FORCEPROP 2 LAST CDS_LIB pure_quanta
J 2
(-6800 2225);
DISPLAY INVISIBLE (-6800 2225);
FORCEPROP 1 LAST PATH I51
J 2
(-6850 2400);
DISPLAY 0.978723 (-6850 2400);
PAINT WHITE (-6850 2400);
DISPLAY INVISIBLE (-6850 2400);
FORCEPROP 1 LAST PART_NUMBER CS31002FB08
J 2
(-6840 2100);
DISPLAY 0.638298 (-6840 2100);
DISPLAY INVISIBLE (-6840 2100);
FORCEADD P1V0_AUX..1
(-6800 2625);
FORCEPROP 3 LASTPIN (-6800 2575) SIG_NAME P1V8_AUX\g
J 0
(-6790 2585);
DISPLAY 0.659574 (-6790 2585);
PAINT MONO (-6790 2585);
DISPLAY INVISIBLE (-6790 2585);
FORCEPROP 1 LAST HDL_POWER P1V8_AUX
J 1
(-6790 2665);
DISPLAY 0.489362 (-6790 2665);
PAINT GREEN (-6790 2665);
FORCEPROP 2 LAST CDS_LIB pure_quanta_power
J 0
(-6800 2625);
DISPLAY INVISIBLE (-6800 2625);
FORCEPROP 1 LAST PATH I52
J 0
(-6750 2650);
DISPLAY 0.872340 (-6750 2650);
PAINT AQUA (-6750 2650);
DISPLAY INVISIBLE (-6750 2650);
FORCEADD UNIVERSAL_POWER..1
(-8825 4400);
FORCEPROP 3 LASTPIN (-8825 4350) SIG_NAME P12V_AUX\g
J 0
(-8815 4360);
DISPLAY 0.659574 (-8815 4360);
PAINT MONO (-8815 4360);
DISPLAY INVISIBLE (-8815 4360);
FORCEPROP 1 LAST HDL_POWER P12V_AUX
J 1
(-8825 4450);
DISPLAY 0.872340 (-8825 4450);
PAINT GREEN (-8825 4450);
FORCEPROP 2 LAST CDS_LIB pure_quanta_power
J 0
(-8825 4400);
DISPLAY INVISIBLE (-8825 4400);
FORCEPROP 1 LAST PATH I53
J 0
(-8775 4425);
DISPLAY 0.872340 (-8775 4425);
PAINT AQUA (-8775 4425);
DISPLAY INVISIBLE (-8775 4425);
FORCEADD Q_RES_4P_12..1
R 1
(-7925 4050);
FORCEPROP 1 LAST LOCATION R1837
J 0
(-8050 4350);
DISPLAY 0.680851 (-8050 4350);
PAINT GREEN (-8050 4350);
FORCEPROP 0 LAST $SEC 1
R 1
J 0
(-8050 4400);
DISPLAY 0.680851 (-8050 4400);
PAINT MONO (-8050 4400);
DISPLAY INVISIBLE (-8050 4400);
FORCEPROP 0 LAST CDS_SEC 1
R 1
J 0
(-8375 3900);
DISPLAY 1.021277 (-8375 3900);
DISPLAY INVISIBLE (-8375 3900);
FORCEPROP 0 LASTPIN (-8050 4050) $PN 1
J 2
(-8060 4060);
DISPLAY 0.680851 (-8060 4060);
PAINT MONO (-8060 4060);
FORCEPROP 0 LASTPIN (-7800 4050) $PN 2
J 0
(-7790 4060);
DISPLAY 0.680851 (-7790 4060);
PAINT MONO (-7790 4060);
FORCEPROP 0 LASTPIN (-7950 3950) $PN 3
R 1
J 2
(-7960 3940);
DISPLAY 0.680851 (-7960 3940);
PAINT MONO (-7960 3940);
FORCEPROP 0 LASTPIN (-7900 3950) $PN 4
R 1
J 2
(-7910 3940);
DISPLAY 0.680851 (-7910 3940);
PAINT MONO (-7910 3940);
FORCEPROP 1 LAST MATERIAL CHIP
J 0
(-8050 4250);
DISPLAY 0.574468 (-8050 4250);
PAINT GREEN (-8050 4250);
FORCEPROP 2 LAST TOLERANCE 1%
J 0
(-7800 4125);
DISPLAY 0.638298 (-7800 4125);
FORCEPROP 2 LAST WATTAGE 3W
J 0
(-7875 4125);
DISPLAY 0.638298 (-7875 4125);
FORCEPROP 2 LAST VALUE 0.001
J 0
(-8050 4125);
DISPLAY 0.638298 (-8050 4125);
FORCEPROP 2 LAST PART_TYPE SMLF
J 0
(-8050 4175);
DISPLAY 0.638298 (-8050 4175);
FORCEPROP 1 LAST NEEDS_NO_SIZE TRUE
R 1
J 0
(-7924 4050);
DISPLAY 0.468085 (-7924 4050);
PAINT GREEN (-7924 4050);
DISPLAY INVISIBLE (-7924 4050);
FORCEPROP 1 LAST CDS_LMAN_SYM_OUTLINE -50,75,50,-75
R 1
J 0
(-7925 4050);
DISPLAY 0.468085 (-7925 4050);
PAINT GREEN (-7925 4050);
DISPLAY INVISIBLE (-7925 4050);
FORCEPROP 2 LAST CDS_LIB pure_quanta
R 1
J 0
(-7925 4050);
DISPLAY INVISIBLE (-7925 4050);
FORCEPROP 1 LAST PATH I54
R 1
J 0
(-7925 4050);
DISPLAY 0.723404 (-7925 4050);
PAINT GREEN (-7925 4050);
DISPLAY INVISIBLE (-7925 4050);
FORCEPROP 1 LAST PART_NUMBER SP_CS+001DFR10
J 0
(-8050 4300);
DISPLAY 0.574468 (-8050 4300);
PAINT GREEN (-8050 4300);
DISPLAY INVISIBLE (-8050 4300);
FORCEADD UNIVERSAL_POWER..1
(-7075 4400);
FORCEPROP 3 LASTPIN (-7075 4350) SIG_NAME P12V_MEM_CPU1\g
J 0
(-7065 4360);
DISPLAY 0.659574 (-7065 4360);
PAINT MONO (-7065 4360);
DISPLAY INVISIBLE (-7065 4360);
FORCEPROP 1 LAST HDL_POWER P12V_MEM_CPU1
J 1
(-7075 4450);
DISPLAY 0.872340 (-7075 4450);
PAINT GREEN (-7075 4450);
FORCEPROP 2 LAST CDS_LIB pure_quanta_power
J 0
(-7075 4400);
DISPLAY INVISIBLE (-7075 4400);
FORCEPROP 1 LAST PATH I55
J 0
(-7025 4425);
DISPLAY 0.872340 (-7025 4425);
PAINT AQUA (-7025 4425);
DISPLAY INVISIBLE (-7025 4425);
FORCEADD UNIVERSAL_POWER..1
(-8850 5850);
FORCEPROP 3 LASTPIN (-8850 5800) SIG_NAME P12V_AUX\g
J 0
(-8840 5810);
DISPLAY 0.659574 (-8840 5810);
PAINT MONO (-8840 5810);
DISPLAY INVISIBLE (-8840 5810);
FORCEPROP 1 LAST HDL_POWER P12V_AUX
J 1
(-8850 5900);
DISPLAY 0.872340 (-8850 5900);
PAINT GREEN (-8850 5900);
FORCEPROP 2 LAST CDS_LIB pure_quanta_power
J 0
(-8850 5850);
DISPLAY INVISIBLE (-8850 5850);
FORCEPROP 1 LAST PATH I56
J 0
(-8800 5875);
DISPLAY 0.872340 (-8800 5875);
PAINT AQUA (-8800 5875);
DISPLAY INVISIBLE (-8800 5875);
FORCEADD UNIVERSAL_POWER..1
(-7100 5850);
FORCEPROP 3 LASTPIN (-7100 5800) SIG_NAME P12V_MEM_CPU0\g
J 0
(-7090 5810);
DISPLAY 0.659574 (-7090 5810);
PAINT MONO (-7090 5810);
DISPLAY INVISIBLE (-7090 5810);
FORCEPROP 1 LAST HDL_POWER P12V_MEM_CPU0
J 1
(-7100 5900);
DISPLAY 0.872340 (-7100 5900);
PAINT GREEN (-7100 5900);
FORCEPROP 2 LAST CDS_LIB pure_quanta_power
J 0
(-7100 5850);
DISPLAY INVISIBLE (-7100 5850);
FORCEPROP 1 LAST PATH I57
J 0
(-7050 5875);
DISPLAY 0.872340 (-7050 5875);
PAINT AQUA (-7050 5875);
DISPLAY INVISIBLE (-7050 5875);
FORCEADD Q_RES_4P_12..1
R 1
(-7950 5500);
FORCEPROP 1 LAST LOCATION R1838
J 0
(-8075 5800);
DISPLAY 0.680851 (-8075 5800);
PAINT GREEN (-8075 5800);
FORCEPROP 0 LAST $SEC 1
R 1
J 0
(-8075 5850);
DISPLAY 0.680851 (-8075 5850);
PAINT MONO (-8075 5850);
DISPLAY INVISIBLE (-8075 5850);
FORCEPROP 0 LAST CDS_SEC 1
R 1
J 0
(-8400 5350);
DISPLAY 1.021277 (-8400 5350);
DISPLAY INVISIBLE (-8400 5350);
FORCEPROP 0 LASTPIN (-8075 5500) $PN 1
J 2
(-8085 5510);
DISPLAY 0.680851 (-8085 5510);
PAINT MONO (-8085 5510);
FORCEPROP 0 LASTPIN (-7825 5500) $PN 2
J 0
(-7815 5510);
DISPLAY 0.680851 (-7815 5510);
PAINT MONO (-7815 5510);
FORCEPROP 0 LASTPIN (-7975 5400) $PN 3
R 1
J 2
(-7985 5390);
DISPLAY 0.680851 (-7985 5390);
PAINT MONO (-7985 5390);
FORCEPROP 0 LASTPIN (-7925 5400) $PN 4
R 1
J 2
(-7935 5390);
DISPLAY 0.680851 (-7935 5390);
PAINT MONO (-7935 5390);
FORCEPROP 2 LAST WATTAGE 3W
J 0
(-7900 5575);
DISPLAY 0.638298 (-7900 5575);
FORCEPROP 1 LAST MATERIAL CHIP
J 0
(-8075 5700);
DISPLAY 0.574468 (-8075 5700);
PAINT GREEN (-8075 5700);
FORCEPROP 2 LAST VALUE 0.001
J 0
(-8075 5575);
DISPLAY 0.638298 (-8075 5575);
FORCEPROP 2 LAST TOLERANCE 1%
J 0
(-7825 5575);
DISPLAY 0.638298 (-7825 5575);
FORCEPROP 2 LAST PART_TYPE SMLF
J 0
(-8075 5625);
DISPLAY 0.638298 (-8075 5625);
FORCEPROP 1 LAST NEEDS_NO_SIZE TRUE
R 1
J 0
(-7949 5500);
DISPLAY 0.468085 (-7949 5500);
PAINT GREEN (-7949 5500);
DISPLAY INVISIBLE (-7949 5500);
FORCEPROP 1 LAST CDS_LMAN_SYM_OUTLINE -50,75,50,-75
R 1
J 0
(-7950 5500);
DISPLAY 0.468085 (-7950 5500);
PAINT GREEN (-7950 5500);
DISPLAY INVISIBLE (-7950 5500);
FORCEPROP 2 LAST CDS_LIB pure_quanta
R 1
J 0
(-7950 5500);
DISPLAY INVISIBLE (-7950 5500);
FORCEPROP 1 LAST PATH I58
R 1
J 0
(-7950 5500);
DISPLAY 0.723404 (-7950 5500);
PAINT GREEN (-7950 5500);
DISPLAY INVISIBLE (-7950 5500);
FORCEPROP 1 LAST PART_NUMBER SP_CS+001DFR10
J 0
(-8075 5750);
DISPLAY 0.574468 (-8075 5750);
PAINT GREEN (-8075 5750);
DISPLAY INVISIBLE (-8075 5750);
FORCEADD Q_RES..1
(-5475 2175);
FORCEPROP 1 LAST LOCATION R1458
J 0
(-5725 2175);
DISPLAY 0.489362 (-5725 2175);
PAINT SKYBLUE (-5725 2175);
FORCEPROP 0 LAST $SEC 1
J 0
(-5575 2225);
DISPLAY 0.680851 (-5575 2225);
PAINT MONO (-5575 2225);
DISPLAY INVISIBLE (-5575 2225);
FORCEPROP 0 LAST CDS_SEC 1
J 0
(-5575 2225);
DISPLAY 0.680851 (-5575 2225);
DISPLAY INVISIBLE (-5575 2225);
FORCEPROP 1 LASTPIN (-5575 2175) $PN 1
J 0
(-5563 2187);
DISPLAY 0.489362 (-5563 2187);
PAINT MONO (-5563 2187);
FORCEPROP 1 LASTPIN (-5375 2175) $PN 2
J 0
(-5413 2187);
DISPLAY 0.489362 (-5413 2187);
PAINT MONO (-5413 2187);
FORCEPROP 1 LAST VALUE 33
J 2
(-5350 2175);
DISPLAY 0.489362 (-5350 2175);
PAINT SKYBLUE (-5350 2175);
FORCEPROP 1 LAST PACK_TYPE 0402LF
J 0
(-5400 2125);
DISPLAY 0.489362 (-5400 2125);
PAINT SKYBLUE (-5400 2125);
DISPLAY INVISIBLE (-5400 2125);
FORCEPROP 1 LAST TOLERANCE 5%
J 0
(-5475 2125);
DISPLAY 0.489362 (-5475 2125);
PAINT SKYBLUE (-5475 2125);
DISPLAY INVISIBLE (-5475 2125);
FORCEPROP 1 LAST MATERIAL CHIP
J 0
(-5325 2175);
DISPLAY 0.489362 (-5325 2175);
PAINT SKYBLUE (-5325 2175);
DISPLAY INVISIBLE (-5325 2175);
FORCEPROP 1 LAST WATTAGE 1/16W
J 2
(-5500 2075);
DISPLAY 0.489362 (-5500 2075);
PAINT SKYBLUE (-5500 2075);
DISPLAY INVISIBLE (-5500 2075);
FORCEPROP 2 LAST CDS_LIB pure_quanta
J 0
(-5475 2175);
DISPLAY INVISIBLE (-5475 2175);
FORCEPROP 2 LAST BOM_COST OCP3.0 
J 0
(-5400 2275);
DISPLAY 0.680851 (-5400 2275);
DISPLAY INVISIBLE (-5400 2275);
FORCEPROP 1 LAST PATH I6
J 0
(-5525 2325);
DISPLAY 0.978723 (-5525 2325);
PAINT WHITE (-5525 2325);
DISPLAY INVISIBLE (-5525 2325);
FORCEPROP 1 LAST PART_NUMBER CS03302JB10
J 0
(-5400 2225);
DISPLAY 0.489362 (-5400 2225);
PAINT SKYBLUE (-5400 2225);
DISPLAY INVISIBLE (-5400 2225);
FORCEADD UNIVERSAL_GND..1
(-4875 1725);
FORCEPROP 3 LASTPIN (-4875 1775) SIG_NAME GND\g
J 0
(-4865 1785);
DISPLAY 0.659574 (-4865 1785);
PAINT MONO (-4865 1785);
DISPLAY INVISIBLE (-4865 1785);
FORCEPROP 2 LAST CDS_LIB pure_quanta_power
J 0
(-4875 1725);
DISPLAY INVISIBLE (-4875 1725);
FORCEPROP 2 LAST BOM_COST VR_SYSTEM
J 0
(-5200 1800);
DISPLAY 0.617021 (-5200 1800);
PAINT PURPLE (-5200 1800);
DISPLAY INVISIBLE (-5200 1800);
FORCEPROP 1 LAST HDL_POWER GND
J 1
(-4850 1650);
DISPLAY 0.872340 (-4850 1650);
PAINT GREEN (-4850 1650);
DISPLAY INVISIBLE (-4850 1650);
FORCEPROP 1 LAST PATH I7
J 0
(-4800 1725);
DISPLAY 0.872340 (-4800 1725);
PAINT AQUA (-4800 1725);
DISPLAY INVISIBLE (-4800 1725);
FORCEADD SN74LVC1G11DCKR..1
(-4500 2025);
FORCEPROP 1 LAST LOCATION U38
J 0
(-4650 2400);
DISPLAY 0.489362 (-4650 2400);
PAINT SKYBLUE (-4650 2400);
FORCEPROP 0 LAST $SEC 1
J 0
(-4650 2550);
DISPLAY 0.680851 (-4650 2550);
PAINT MONO (-4650 2550);
DISPLAY INVISIBLE (-4650 2550);
FORCEPROP 0 LAST CDS_SEC 1
J 0
(-4650 2550);
DISPLAY 0.680851 (-4650 2550);
DISPLAY INVISIBLE (-4650 2550);
FORCEPROP 0 LASTPIN (-4800 2175) $PN 1
J 2
(-4810 2185);
DISPLAY 0.489362 (-4810 2185);
PAINT MONO (-4810 2185);
FORCEPROP 0 LASTPIN (-4800 2075) $PN 3
J 2
(-4810 2085);
DISPLAY 0.489362 (-4810 2085);
PAINT MONO (-4810 2085);
FORCEPROP 0 LASTPIN (-4800 1975) $PN 6
J 2
(-4810 1985);
DISPLAY 0.489362 (-4810 1985);
PAINT MONO (-4810 1985);
FORCEPROP 0 LASTPIN (-4800 1875) $PN 2
J 2
(-4810 1885);
DISPLAY 0.489362 (-4810 1885);
PAINT MONO (-4810 1885);
FORCEPROP 0 LASTPIN (-4200 2175) $PN 5
J 0
(-4190 2185);
DISPLAY 0.489362 (-4190 2185);
PAINT MONO (-4190 2185);
FORCEPROP 0 LASTPIN (-4200 2025) $PN 4
J 0
(-4190 2035);
DISPLAY 0.489362 (-4190 2035);
PAINT MONO (-4190 2035);
FORCEPROP 2 LAST VALUE SN74LVC1G11DCKR
J 0
(-4650 2450);
DISPLAY 0.489362 (-4650 2450);
PAINT SKYBLUE (-4650 2450);
FORCEPROP 1 LAST MATERIAL IC
J 0
(-4650 2250);
DISPLAY 0.489362 (-4650 2250);
PAINT SKYBLUE (-4650 2250);
FORCEPROP 2 LAST PART_TYPE SMLF
J 0
(-4650 2500);
DISPLAY 0.680851 (-4650 2500);
FORCEPROP 2 LAST CDS_LIB pure_quanta
J 0
(-4500 2025);
DISPLAY INVISIBLE (-4500 2025);
FORCEPROP 1 LAST NEEDS_NO_SIZE TRUE
J 0
(-4500 2025);
DISPLAY 0.723404 (-4500 2025);
PAINT GREEN (-4500 2025);
DISPLAY INVISIBLE (-4500 2025);
FORCEPROP 1 LAST CDS_LMAN_SYM_OUTLINE -150,200,150,-200
J 0
(-4500 2025);
DISPLAY 0.468085 (-4500 2025);
PAINT GREEN (-4500 2025);
DISPLAY INVISIBLE (-4500 2025);
FORCEPROP 1 LAST PATH I8
J 0
(-4500 2025);
DISPLAY 0.723404 (-4500 2025);
PAINT GREEN (-4500 2025);
DISPLAY INVISIBLE (-4500 2025);
FORCEPROP 1 LAST PART_NUMBER ALLVC1G1000
J 0
(-4650 2325);
DISPLAY 0.489362 (-4650 2325);
PAINT SKYBLUE (-4650 2325);
DISPLAY INVISIBLE (-4650 2325);
FORCEADD QUANTA_TITLE_BLOCK_C..1
(0 0);
FORCEPROP 0 LAST CDS_CON_LAST_MODIFIED Thu Sep 14 16:12:45 2023
J 0
(-1885 15);
DISPLAY INVISIBLE (-1885 15);
FORCEPROP 1 LAST CUSTOM_TXT_CDS <CON_LAST_MODIFIED>
J 0
(-1885 15);
DISPLAY 0.978723 (-1885 15);
FORCEPROP 2 LAST CUSTOM_TXT_CDS <XR_PAGE_TITLE>
J 0
(-7890 5250);
DISPLAY 0.638298 (-7890 5250);
PAINT PINK (-7890 5250);
DISPLAY INVISIBLE (-7890 5250);
FORCEPROP 1 LAST CUSTOM_TXT_CDS <NAME_2>
J 0
(-3175 50);
FORCEPROP 1 LAST CUSTOM_TXT_CDS <NAME_1>
J 0
(-3175 175);
FORCEPROP 1 LAST CUSTOM_TXT_CDS <Q_NUMBER>
J 0
(-1403 103);
DISPLAY 1.212766 (-1403 103);
FORCEPROP 1 LAST CUSTOM_TXT_CDS <Q_PROJ>
J 0
(-2382 102);
DISPLAY 1.212766 (-2382 102);
FORCEPROP 1 LAST CUSTOM_TXT_CDS <Q_REV>
J 0
(-184 103);
DISPLAY 1.212766 (-184 103);
FORCEPROP 1 LAST CUSTOM_TXT_CDS <CON_PAGE_NUM> OF <CON_TOTAL_PAGES>
J 0
(-446 18);
DISPLAY 0.978723 (-446 18);
FORCEPROP 1 LAST Q_TITLE P12V_MEM MOS SWITCH
J 0
(-9366 26);
DISPLAY 2.446809 (-9366 26);
PAINT GREEN (-9366 26);
FORCEPROP 2 LAST PAGE_BORDER TRUE
J 0
(-7890 5250);
DISPLAY 0.638298 (-7890 5250);
PAINT PINK (-7890 5250);
DISPLAY INVISIBLE (-7890 5250);
FORCEPROP 1 LAST CDS_LMAN_SYM_OUTLINE -9475,6775,100,-125
J 0
(0 0);
DISPLAY 0.468085 (0 0);
PAINT GREEN (0 0);
DISPLAY INVISIBLE (0 0);
FORCEPROP 2 LAST CDS_LIB pure_quanta
J 0
(0 0);
DISPLAY INVISIBLE (0 0);
FORCEPROP 2 LAST CDS_XR_PAGE_TITLE CR-260 : @T6G_MB_LIB.T6G(SCH_1):PAGE260
J 0
(-7890 5250);
DISPLAY 0.638298 (-7890 5250);
PAINT PINK (-7890 5250);
DISPLAY INVISIBLE (-7890 5250);
FORCEPROP 1 LAST Q_DEPT BU9
J 1
(-3763 49);
DISPLAY 1.957447 (-3763 49);
PAINT GREEN (-3763 49);
DISPLAY INVISIBLE (-3763 49);
FORCEPROP 1 LAST COMMENT_BODY TRUE
J 0
(12 -13);
DISPLAY 0.978723 (12 -13);
PAINT GREEN (12 -13);
DISPLAY INVISIBLE (12 -13);
WIRE 16 -1 (-4800 1875)(-4875 1875);
WIRE 16 -1 (-4875 1875)(-4875 1775);
WIRE 16 -1 (-6800 2325)(-6800 2575);
WIRE 16 -1 (-3225 1675)(-3225 1575);
WIRE 16 -1 (-4325 4750)(-4325 4875);
WIRE 16 -1 (-4425 6050)(-4425 6175);
WIRE 16 -1 (-5500 6075)(-5500 6250);
WIRE 16 -1 (-6275 5850)(-6275 6025);
WIRE 16 -1 (-4750 5525)(-4725 5525);
WIRE 16 -1 (-4500 4200)(-4475 4200);
WIRE 16 -1 (-5100 4200)(-5125 4200);
WIRE 16 -1 (-5350 5525)(-5375 5525);
WIRE 16 -1 (-5425 4800)(-5425 4900);
WIRE 16 -1 (-6175 4525)(-6175 4700);
WIRE 16 -1 (-6275 5100)(-6275 5150);
WIRE 16 -1 (-6175 3775)(-6175 3825);
WIRE 16 -1 (-3750 2250)(-3750 2200);
WIRE 16 -1 (-4800 1975)(-6800 1975);
FORCEPROP 2 LAST SIG_NAME PU_U38_6
J 0
(-5260 1985);
DISPLAY 0.489362 (-5260 1985);
FORCEPROP 2 LASTPROP $XRERR UNIQUE?
J 0
(-5500 1985);
DISPLAY 0.638298 (-5500 1985);
PAINT MONO (-5500 1985);
DISPLAY INVISIBLE (-5500 1985);
WIRE 16 -1 (-6800 2125)(-6800 1975);
WIRE 16 -1 (-7100 5800)(-7100 5500);
WIRE 16 -1 (-7100 5500)(-7825 5500);
WIRE 16 -1 (-8850 5500)(-8075 5500);
WIRE 16 -1 (-8850 5800)(-8850 5500);
WIRE 16 -1 (-7075 4350)(-7075 4050);
WIRE 16 -1 (-7075 4050)(-7800 4050);
WIRE 16 -1 (-8825 4050)(-8050 4050);
WIRE 16 -1 (-8825 4350)(-8825 4050);
WIRE 16 -1 (-4000 2475)(-3750 2475);
WIRE 16 -1 (-4000 2475)(-4000 2175);
WIRE 16 -1 (-4000 2550)(-4000 2475);
WIRE 16 -1 (-3750 2475)(-3750 2450);
WIRE 16 -1 (-4000 2175)(-4200 2175);
WIRE 16 -1 (-5575 2075)(-6325 2075);
FORCEPROP 2 LAST SIG_NAME PWRGD_P12V_MEM_CPU1
J 0
(-6310 2100);
DISPLAY 0.489362 (-6310 2100);
WIRE 16 -1 (-7925 5400)(-7925 5350);
WIRE 16 -1 (-7925 5350)(-6775 5350);
FORCEPROP 0 LAST CDS_PHYS_NET_NAME TP_P12V_AUX_CPU0_DIMM_ISEN_N
J 0
(-7735 5381);
PAINT MONO (-7735 5381);
DISPLAY INVISIBLE (-7735 5381);
FORCEPROP 2 LAST SIG_NAME TP_P12V_AUX_CPU0_DIMM_ISEN_N
J 0
(-7635 5360);
DISPLAY 0.446809 (-7635 5360);
PAINT WHITE (-7635 5360);
FORCEPROP 2 LASTPROP $XRERR UNIQUE?
J 0
(-6745 5350);
DISPLAY 0.638298 (-6745 5350);
PAINT MONO (-6745 5350);
DISPLAY INVISIBLE (-6745 5350);
WIRE 16 -1 (-8975 3900)(-7950 3900);
FORCEPROP 0 LAST CDS_PHYS_NET_NAME TP_P12V_AUX_CPU1_DIMM_ISEN_P
J 0
(-8885 3931);
PAINT MONO (-8885 3931);
DISPLAY INVISIBLE (-8885 3931);
FORCEPROP 2 LAST SIG_NAME TP_P12V_AUX_CPU1_DIMM_ISEN_P
J 0
(-8785 3910);
DISPLAY 0.446809 (-8785 3910);
PAINT WHITE (-8785 3910);
FORCEPROP 2 LASTPROP $XRERR UNIQUE?
J 0
(-9215 3900);
DISPLAY 0.638298 (-9215 3900);
PAINT MONO (-9215 3900);
DISPLAY INVISIBLE (-9215 3900);
WIRE 16 -1 (-7950 3950)(-7950 3900);
WIRE 16 -1 (-7900 3900)(-6775 3900);
FORCEPROP 0 LAST CDS_PHYS_NET_NAME TP_P12V_AUX_CPU1_DIMM_ISEN_N
J 0
(-7710 3931);
PAINT MONO (-7710 3931);
DISPLAY INVISIBLE (-7710 3931);
FORCEPROP 2 LAST SIG_NAME TP_P12V_AUX_CPU1_DIMM_ISEN_N
J 0
(-7610 3910);
DISPLAY 0.446809 (-7610 3910);
PAINT WHITE (-7610 3910);
FORCEPROP 2 LASTPROP $XRERR UNIQUE?
J 0
(-6745 3900);
DISPLAY 0.638298 (-6745 3900);
PAINT MONO (-6745 3900);
DISPLAY INVISIBLE (-6745 3900);
WIRE 16 -1 (-7900 3950)(-7900 3900);
WIRE 16 -1 (-9000 5350)(-7975 5350);
FORCEPROP 0 LAST CDS_PHYS_NET_NAME TP_P12V_AUX_CPU0_DIMM_ISEN_P
J 0
(-8910 5381);
PAINT MONO (-8910 5381);
DISPLAY INVISIBLE (-8910 5381);
FORCEPROP 2 LAST SIG_NAME TP_P12V_AUX_CPU0_DIMM_ISEN_P
J 0
(-8810 5360);
DISPLAY 0.446809 (-8810 5360);
PAINT WHITE (-8810 5360);
FORCEPROP 2 LASTPROP $XRERR UNIQUE?
J 0
(-9240 5350);
DISPLAY 0.638298 (-9240 5350);
PAINT MONO (-9240 5350);
DISPLAY INVISIBLE (-9240 5350);
WIRE 16 -1 (-7975 5400)(-7975 5350);
WIRE 16 -1 (-5375 2175)(-4800 2175);
FORCEPROP 2 LAST SIG_NAME PWRGD_P12V_MEM_CPU0_R
J 0
(-5285 2200);
DISPLAY 0.382979 (-5285 2200);
FORCEPROP 2 LASTPROP $XRERR UNIQUE?
J 0
(-5525 2200);
DISPLAY 0.638298 (-5525 2200);
PAINT MONO (-5525 2200);
DISPLAY INVISIBLE (-5525 2200);
WIRE 16 -1 (-4375 3950)(-4375 4150);
WIRE 16 -1 (-4375 3950)(-5425 3950);
FORCEPROP 2 LAST SIG_NAME PWRGD_P12V_MEM_CPU1_EN_N
J 0
(-5085 3960);
DISPLAY 0.489362 (-5085 3960);
FORCEPROP 2 LASTPROP $XRERR UNIQUE?
J 0
(-5325 3960);
DISPLAY 0.638298 (-5325 3960);
PAINT MONO (-5325 3960);
DISPLAY INVISIBLE (-5325 3960);
WIRE 16 -1 (-4500 4150)(-4375 4150);
WIRE 16 -1 (-5425 4100)(-5425 3950);
WIRE 16 -1 (-5425 4100)(-5100 4100);
WIRE 16 -1 (-5425 4600)(-5425 4100);
WIRE 16 -1 (-4425 5850)(-4425 5625);
FORCEPROP 2 LAST SIG_NAME PWRGD_P12V_MEM_CPU0
J 0
(-4360 5650);
DISPLAY 0.489362 (-4360 5650);
WIRE 16 -1 (-3950 5625)(-4425 5625);
WIRE 16 -1 (-4425 5625)(-4425 5425);
WIRE 16 -1 (-4425 5425)(-4750 5425);
WIRE 16 -1 (-4325 4100)(-4325 4375);
WIRE 16 -1 (-4325 4100)(-4500 4100);
WIRE 16 -1 (-4325 4375)(-3750 4375);
FORCEPROP 2 LAST SIG_NAME PWRGD_P12V_MEM_CPU1
J 0
(-4285 4385);
DISPLAY 0.489362 (-4285 4385);
WIRE 16 -1 (-4325 4550)(-4325 4375);
WIRE 16 -1 (-6175 4150)(-5100 4150);
FORCEPROP 2 LAST SIG_NAME PWRGD_P12V_MEM_CPU1_EN
J 0
(-6135 4160);
DISPLAY 0.489362 (-6135 4160);
FORCEPROP 2 LASTPROP $XRERR UNIQUE?
J 0
(-6375 4160);
DISPLAY 0.638298 (-6375 4160);
PAINT MONO (-6375 4160);
DISPLAY INVISIBLE (-6375 4160);
WIRE 16 -1 (-6175 4325)(-6175 4150);
WIRE 16 -1 (-6175 4150)(-6175 4025);
WIRE 16 -1 (-3675 2025)(-4200 2025);
FORCEPROP 2 LAST SIG_NAME PWRGD_P12V_MEM
J 0
(-4110 2035);
DISPLAY 0.489362 (-4110 2035);
FORCEPROP 2 LASTPROP $XRERR UNIQUE?
J 0
(-4350 2035);
DISPLAY 0.638298 (-4350 2035);
PAINT MONO (-4350 2035);
DISPLAY INVISIBLE (-4350 2035);
WIRE 16 -1 (-5375 2075)(-4800 2075);
FORCEPROP 2 LAST SIG_NAME PWRGD_P12V_MEM_CPU1_R
J 0
(-5285 2100);
DISPLAY 0.382979 (-5285 2100);
FORCEPROP 2 LASTPROP $XRERR UNIQUE?
J 0
(-5525 2100);
DISPLAY 0.638298 (-5525 2100);
PAINT MONO (-5525 2100);
DISPLAY INVISIBLE (-5525 2100);
WIRE 16 -1 (-2900 2025)(-3225 2025);
WIRE 16 -1 (-3225 2025)(-3225 1875);
WIRE 16 -1 (-3225 2025)(-3475 2025);
FORCEPROP 2 LAST SIG_NAME PWRGD_P12V_MEM_R
J 0
(-3275 2035);
DISPLAY 0.489362 (-3275 2035);
WIRE 16 -1 (-4750 5475)(-4650 5475);
WIRE 16 -1 (-4650 5475)(-4650 5275);
WIRE 16 -1 (-4650 5275)(-5500 5275);
FORCEPROP 2 LAST SIG_NAME PWRGD_P12V_MEM_CPU0_EN_N
J 0
(-5260 5285);
DISPLAY 0.489362 (-5260 5285);
FORCEPROP 2 LASTPROP $XRERR UNIQUE?
J 0
(-5500 5285);
DISPLAY 0.638298 (-5500 5285);
PAINT MONO (-5500 5285);
DISPLAY INVISIBLE (-5500 5285);
WIRE 16 -1 (-5500 5275)(-5500 5425);
WIRE 16 -1 (-5500 5425)(-5500 5875);
WIRE 16 -1 (-5350 5425)(-5500 5425);
WIRE 16 -1 (-5350 5475)(-6275 5475);
FORCEPROP 2 LAST SIG_NAME PWRGD_P12V_MEM_CPU0_EN
J 0
(-6210 5485);
DISPLAY 0.489362 (-6210 5485);
FORCEPROP 2 LASTPROP $XRERR UNIQUE?
J 0
(-6450 5485);
DISPLAY 0.638298 (-6450 5485);
PAINT MONO (-6450 5485);
DISPLAY INVISIBLE (-6450 5485);
WIRE 16 -1 (-6275 5650)(-6275 5475);
WIRE 16 -1 (-6275 5475)(-6275 5350);
WIRE 16 -1 (-5575 2175)(-6325 2175);
FORCEPROP 2 LAST SIG_NAME PWRGD_P12V_MEM_CPU0
J 0
(-6310 2200);
DISPLAY 0.489362 (-6310 2200);
DOT 1 (-3225 2025);
DOT 1 (-4000 2475);
DOT 1 (-6175 4150);
DOT 1 (-4325 4375);
DOT 1 (-4425 5625);
DOT 1 (-5500 5425);
DOT 1 (-6275 5475);
DOT 1 (-5425 4100);
QUIT
